(kicad_pcb
	(version 20211014)
	(generator pcbnew)
	(general
    (thickness 1.6)
  )
	(paper "A4")
	(title_block
    (title "SA800U (Snapdragon 845) Baseboard")
    (date "2023-10-19")
    (rev "1.0.3")
    (company "Antmicro Ltd.")
    (comment 1 "www.antmicro.com")
		(comment 9 "footprints 480-486 of 589")
	)
	(layers
    (0 "F.Cu" signal)
    (1 "In1.Cu" power)
    (2 "In2.Cu" signal)
    (3 "In3.Cu" signal)
    (4 "In4.Cu" power)
    (31 "B.Cu" signal)
    (32 "B.Adhes" user "B.Adhesive")
    (33 "F.Adhes" user "F.Adhesive")
    (34 "B.Paste" user)
    (35 "F.Paste" user)
    (36 "B.SilkS" user "B.Silkscreen")
    (37 "F.SilkS" user "F.Silkscreen")
    (38 "B.Mask" user)
    (39 "F.Mask" user)
    (40 "Dwgs.User" user "User.Drawings")
    (41 "Cmts.User" user "User.Comments")
    (42 "Eco1.User" user "User.Eco1")
    (43 "Eco2.User" user "User.Eco2")
    (44 "Edge.Cuts" user)
    (45 "Margin" user)
    (46 "B.CrtYd" user "B.Courtyard")
    (47 "F.CrtYd" user "F.Courtyard")
    (48 "B.Fab" user)
    (49 "F.Fab" user)
  )
	(footprint "sa800u-baseboard-hw-footprints:C_0402_1005Metric" (layer "B.Cu")
    (tedit 616D63CF)
    (at 144.5 124.6 180)
    (descr "Capacitor SMD 0402")
    (tags "capacitor SMD 0402")
    (property "Author" "Antmicro")
    (property "Dielectric" "X5R")
    (property "License" "Apache-2.0")
    (property "MPN" "GRM155R61H104KE14D")
    (property "Manufacturer" "Murata")
    (property "Sheetfile" "hdmi-converter.kicad_sch")
    (property "Sheetname" "HDMI converter")
    (property "Val" "100n")
    (property "Voltage" "50V")
    (attr smd)
    (fp_text reference "C40" (at -2.94 -0.35) (layer "B.SilkS")
      (effects (font (size 0.7 0.7) (thickness 0.15)) (justify left bottom mirror))
    )
    (fp_text value "C_100n_0402" (at 0 -1.4) (layer "B.Fab")
      (effects (font (size 0.7 0.7) (thickness 0.15)) (justify left bottom mirror))
    )
    (fp_text user "License: Apache-2.0" (at -0.932 -5.17) (layer "B.Fab") hide
      (effects (font (size 0.7 0.7) (thickness 0.15)) (justify left bottom mirror))
    )
    (fp_text user "Author: Antmicro" (at -0.932 -4.17) (layer "B.Fab") hide
      (effects (font (size 0.7 0.7) (thickness 0.15)) (justify left bottom mirror))
    )
    (fp_text user "${REFERENCE}" (at -0.932 -3.168) (layer "B.Fab") hide
      (effects (font (size 0.7 0.7) (thickness 0.15)) (justify left bottom mirror))
    )
    (fp_rect (start -0.94 0.47) (end 0.94 -0.47) (layer "B.CrtYd") (width 0.05) (fill none))
    (fp_rect (start -0.499 0.249) (end 0.499 -0.249) (layer "B.Fab") (width 0.15) (fill none))
    (pad "1" smd roundrect (at -0.484 0 180) (size 0.59 0.64) (layers "B.Cu" "B.Paste" "B.Mask") (roundrect_rratio 0.25)
      (net 185 "/HDMI converter/LT9611_VCC33_RX") (pintype "passive"))
    (pad "2" smd roundrect (at 0.484 0 180) (size 0.59 0.64) (layers "B.Cu" "B.Paste" "B.Mask") (roundrect_rratio 0.25)
      (net 1 "GND") (pintype "passive"))
  )
	(footprint "sa800u-baseboard-hw-footprints:C_0402_1005Metric" (layer "B.Cu")
    (tedit 616D63CF)
    (at 143.55 121.4 -90)
    (descr "Capacitor SMD 0402")
    (tags "capacitor SMD 0402")
    (property "Author" "Antmicro")
    (property "Dielectric" "X5R")
    (property "License" "Apache-2.0")
    (property "MPN" "GRM155R61H104KE14D")
    (property "Manufacturer" "Murata")
    (property "Sheetfile" "hdmi-converter.kicad_sch")
    (property "Sheetname" "HDMI converter")
    (property "Val" "100n")
    (property "Voltage" "50V")
    (attr smd)
    (fp_text reference "C41" (at -3.08 -0.46 90) (layer "B.SilkS")
      (effects (font (size 0.7 0.7) (thickness 0.15)) (justify left bottom mirror))
    )
    (fp_text value "C_100n_0402" (at 0 -1.4 90) (layer "B.Fab")
      (effects (font (size 0.7 0.7) (thickness 0.15)) (justify left bottom mirror))
    )
    (fp_text user "${REFERENCE}" (at -0.932 -3.168 90) (layer "B.Fab") hide
      (effects (font (size 0.7 0.7) (thickness 0.15)) (justify left bottom mirror))
    )
    (fp_text user "Author: Antmicro" (at -0.932 -4.17 90) (layer "B.Fab") hide
      (effects (font (size 0.7 0.7) (thickness 0.15)) (justify left bottom mirror))
    )
    (fp_text user "License: Apache-2.0" (at -0.932 -5.17 90) (layer "B.Fab") hide
      (effects (font (size 0.7 0.7) (thickness 0.15)) (justify left bottom mirror))
    )
    (fp_rect (start -0.94 0.47) (end 0.94 -0.47) (layer "B.CrtYd") (width 0.05) (fill none))
    (fp_rect (start -0.499 0.249) (end 0.499 -0.249) (layer "B.Fab") (width 0.15) (fill none))
    (pad "1" smd roundrect (at -0.484 0 270) (size 0.59 0.64) (layers "B.Cu" "B.Paste" "B.Mask") (roundrect_rratio 0.25)
      (net 185 "/HDMI converter/LT9611_VCC33_RX") (pintype "passive"))
    (pad "2" smd roundrect (at 0.484 0 270) (size 0.59 0.64) (layers "B.Cu" "B.Paste" "B.Mask") (roundrect_rratio 0.25)
      (net 1 "GND") (pintype "passive"))
  )
	(footprint "sa800u-baseboard-hw-footprints:C_0603_1608Metric" (layer "B.Cu")
    (tedit 5D5E94D2)
    (at 129.56 126.46 180)
    (descr "Capacitor SMD 0603")
    (tags "capacitor 0603")
    (property "Author" "Antmicro")
    (property "Dielectric" "")
    (property "License" "Apache-2.0")
    (property "MPN" "GRM188R60J226MEA0D")
    (property "Manufacturer" "Murata")
    (property "Sheetfile" "psu.kicad_sch")
    (property "Sheetname" "PSU")
    (property "Val" "22u")
    (property "Voltage" "")
    (attr smd)
    (fp_text reference "C137" (at -1.44 -2.34) (layer "B.SilkS")
      (effects (font (size 0.7 0.7) (thickness 0.15)) (justify left bottom mirror))
    )
    (fp_text value "C_22u_0603" (at 0 -1.6) (layer "B.Fab")
      (effects (font (size 0.7 0.7) (thickness 0.15)) (justify left bottom mirror))
    )
    (fp_text user "License: Apache-2.0" (at -1.682 -5.895) (layer "B.Fab") hide
      (effects (font (size 0.7 0.7) (thickness 0.15)) (justify left bottom mirror))
    )
    (fp_text user "${REFERENCE}" (at -1.682 -3.895) (layer "B.Fab") hide
      (effects (font (size 0.7 0.7) (thickness 0.15)) (justify left bottom mirror))
    )
    (fp_text user "Author: Antmicro" (at -1.682 -4.894) (layer "B.Fab") hide
      (effects (font (size 0.7 0.7) (thickness 0.15)) (justify left bottom mirror))
    )
    (fp_line (start -0.3 -0.3) (end 0.3 -0.3) (layer "B.SilkS") (width 0.15))
    (fp_line (start -0.3 0.3) (end 0.3 0.3) (layer "B.SilkS") (width 0.15))
    (fp_rect (start -1.24 0.7) (end 1.24 -0.7) (layer "B.CrtYd") (width 0.05) (fill none))
    (fp_rect (start -0.8 0.4) (end 0.8 -0.4) (layer "B.Fab") (width 0.15) (fill none))
    (pad "1" smd roundrect (at -0.7 0 180) (size 0.6 0.8) (layers "B.Cu" "B.Paste" "B.Mask") (roundrect_rratio 0.2)
      (net 138 "1V2_SYS") (pintype "passive"))
    (pad "2" smd roundrect (at 0.7 0 180) (size 0.6 0.8) (layers "B.Cu" "B.Paste" "B.Mask") (roundrect_rratio 0.2)
      (net 1 "GND") (pintype "passive"))
  )
	(footprint "sa800u-baseboard-hw-footprints:C_0402_1005Metric" (layer "B.Cu")
    (tedit 616D63CF)
    (at 134.600003 122.066849 180)
    (descr "Capacitor SMD 0402")
    (tags "capacitor SMD 0402")
    (property "Author" "Antmicro")
    (property "DNP" "DNP")
    (property "Dielectric" "")
    (property "License" "Apache-2.0")
    (property "MPN" "CC0402MRX5R5BB106")
    (property "Manufacturer" "Yaego")
    (property "Sheetfile" "hdmi-converter.kicad_sch")
    (property "Sheetname" "HDMI converter")
    (property "Val" "10u")
    (property "Voltage" "")
    (attr exclude_from_pos_files)
    (fp_text reference "C22" (at 0.820003 -0.453151) (layer "B.SilkS")
      (effects (font (size 0.7 0.7) (thickness 0.15)) (justify left bottom mirror))
    )
    (fp_text value "C_10u_0402" (at 0 -1.4) (layer "B.Fab")
      (effects (font (size 0.7 0.7) (thickness 0.15)) (justify left bottom mirror))
    )
    (fp_text user "Author: Antmicro" (at -0.932 -4.17) (layer "B.Fab") hide
      (effects (font (size 0.7 0.7) (thickness 0.15)) (justify left bottom mirror))
    )
    (fp_text user "License: Apache-2.0" (at -0.932 -5.17) (layer "B.Fab") hide
      (effects (font (size 0.7 0.7) (thickness 0.15)) (justify left bottom mirror))
    )
    (fp_text user "${REFERENCE}" (at -0.932 -3.168) (layer "B.Fab") hide
      (effects (font (size 0.7 0.7) (thickness 0.15)) (justify left bottom mirror))
    )
    (fp_rect (start -0.94 0.47) (end 0.94 -0.47) (layer "B.CrtYd") (width 0.05) (fill none))
    (fp_rect (start -0.499 0.249) (end 0.499 -0.249) (layer "B.Fab") (width 0.15) (fill none))
    (pad "1" smd roundrect (at -0.484 0 180) (size 0.59 0.64) (layers "B.Cu" "B.Paste" "B.Mask") (roundrect_rratio 0.25)
      (net 188 "/HDMI converter/LT9611_VDD12") (pintype "passive"))
    (pad "2" smd roundrect (at 0.484 0 180) (size 0.59 0.64) (layers "B.Cu" "B.Paste" "B.Mask") (roundrect_rratio 0.25)
      (net 1 "GND") (pintype "passive"))
  )
	(footprint "sa800u-baseboard-hw-footprints:R_0603_1608Metric" (layer "B.Cu")
    (tedit 5D5D3E92)
    (at 68.7 118.55 90)
    (descr "Resistor SMD 0603")
    (tags "resistor SMD 0603")
    (property "Author" "Antmicro")
    (property "DNP" "DNP")
    (property "License" "Apache-2.0")
    (property "MPN" "CR0603-FX-1002ELF")
    (property "Manufacturer" "Bourns")
    (property "Sheetfile" "poe.kicad_sch")
    (property "Sheetname" "PoE")
    (property "Tolerance" "1%")
    (property "Val" "10k")
    (attr exclude_from_pos_files)
    (fp_text reference "R150" (at 1.4 -0.54 270) (layer "B.SilkS")
      (effects (font (size 0.7 0.7) (thickness 0.15)) (justify left bottom mirror))
    )
    (fp_text value "R_10k_0603" (at 0 -1.6 270) (layer "B.Fab")
      (effects (font (size 0.7 0.7) (thickness 0.15)) (justify left bottom mirror))
    )
    (fp_text user "License: Apache-2.0" (at -1.25 -5.9 270) (layer "B.Fab") hide
      (effects (font (size 0.7 0.7) (thickness 0.15)) (justify left bottom mirror))
    )
    (fp_text user "Author: Antmicro" (at -1.25 -4.9 270) (layer "B.Fab") hide
      (effects (font (size 0.7 0.7) (thickness 0.15)) (justify left bottom mirror))
    )
    (fp_text user "${REFERENCE}" (at -1.25 -3.898 270) (layer "B.Fab") hide
      (effects (font (size 0.7 0.7) (thickness 0.15)) (justify left bottom mirror))
    )
    (fp_line (start -0.3 -0.3) (end 0.3 -0.3) (layer "B.SilkS") (width 0.15))
    (fp_line (start -0.3 0.3) (end 0.3 0.3) (layer "B.SilkS") (width 0.15))
    (fp_rect (start -1.25 0.7) (end 1.25 -0.7) (layer "B.CrtYd") (width 0.05) (fill none))
    (fp_rect (start -0.8 0.4) (end 0.8 -0.4) (layer "B.Fab") (width 0.15) (fill none))
    (pad "1" smd roundrect (at -0.7 0 90) (size 0.6 0.8) (layers "B.Cu" "B.Paste" "B.Mask") (roundrect_rratio 0.2)
      (net 380 "Net-(D32-Pad1)") (pintype "passive"))
    (pad "2" smd roundrect (at 0.7 0 90) (size 0.6 0.8) (layers "B.Cu" "B.Paste" "B.Mask") (roundrect_rratio 0.2)
      (net 7 "GNDD") (pintype "passive"))
  )
	(footprint "sa800u-baseboard-hw-footprints:C_0402_1005Metric" (layer "B.Cu")
    (tedit 616D63CF)
    (at 144.5 125.6 180)
    (descr "Capacitor SMD 0402")
    (tags "capacitor SMD 0402")
    (property "Author" "Antmicro")
    (property "Dielectric" "X5R")
    (property "License" "Apache-2.0")
    (property "MPN" "GRM155R61H104KE14D")
    (property "Manufacturer" "Murata")
    (property "Sheetfile" "hdmi-converter.kicad_sch")
    (property "Sheetname" "HDMI converter")
    (property "Val" "100n")
    (property "Voltage" "50V")
    (attr smd)
    (fp_text reference "C33" (at -2.94 -0.35) (layer "B.SilkS")
      (effects (font (size 0.7 0.7) (thickness 0.15)) (justify left bottom mirror))
    )
    (fp_text value "C_100n_0402" (at 0 -1.4) (layer "B.Fab")
      (effects (font (size 0.7 0.7) (thickness 0.15)) (justify left bottom mirror))
    )
    (fp_text user "${REFERENCE}" (at -0.932 -3.168) (layer "B.Fab") hide
      (effects (font (size 0.7 0.7) (thickness 0.15)) (justify left bottom mirror))
    )
    (fp_text user "License: Apache-2.0" (at -0.932 -5.17) (layer "B.Fab") hide
      (effects (font (size 0.7 0.7) (thickness 0.15)) (justify left bottom mirror))
    )
    (fp_text user "Author: Antmicro" (at -0.932 -4.17) (layer "B.Fab") hide
      (effects (font (size 0.7 0.7) (thickness 0.15)) (justify left bottom mirror))
    )
    (fp_rect (start -0.94 0.47) (end 0.94 -0.47) (layer "B.CrtYd") (width 0.05) (fill none))
    (fp_rect (start -0.499 0.249) (end 0.499 -0.249) (layer "B.Fab") (width 0.15) (fill none))
    (pad "1" smd roundrect (at -0.484 0 180) (size 0.59 0.64) (layers "B.Cu" "B.Paste" "B.Mask") (roundrect_rratio 0.25)
      (net 188 "/HDMI converter/LT9611_VDD12") (pintype "passive"))
    (pad "2" smd roundrect (at 0.484 0 180) (size 0.59 0.64) (layers "B.Cu" "B.Paste" "B.Mask") (roundrect_rratio 0.25)
      (net 1 "GND") (pintype "passive"))
  )
	(footprint "sa800u-baseboard-hw-footprints:C_0402_1005Metric" (layer "B.Cu")
    (tedit 616D63CF)
    (at 144.5 126.6 180)
    (descr "Capacitor SMD 0402")
    (tags "capacitor SMD 0402")
    (property "Author" "Antmicro")
    (property "Dielectric" "X5R")
    (property "License" "Apache-2.0")
    (property "MPN" "GRM155R61H104KE14D")
    (property "Manufacturer" "Murata")
    (property "Sheetfile" "hdmi-converter.kicad_sch")
    (property "Sheetname" "HDMI converter")
    (property "Val" "100n")
    (property "Voltage" "50V")
    (attr smd)
    (fp_text reference "C35" (at -2.94 -0.35) (layer "B.SilkS")
      (effects (font (size 0.7 0.7) (thickness 0.15)) (justify left bottom mirror))
    )
    (fp_text value "C_100n_0402" (at 0 -1.4) (layer "B.Fab")
      (effects (font (size 0.7 0.7) (thickness 0.15)) (justify left bottom mirror))
    )
    (fp_text user "${REFERENCE}" (at -0.932 -3.168) (layer "B.Fab") hide
      (effects (font (size 0.7 0.7) (thickness 0.15)) (justify left bottom mirror))
    )
    (fp_text user "License: Apache-2.0" (at -0.932 -5.17) (layer "B.Fab") hide
      (effects (font (size 0.7 0.7) (thickness 0.15)) (justify left bottom mirror))
    )
    (fp_text user "Author: Antmicro" (at -0.932 -4.17) (layer "B.Fab") hide
      (effects (font (size 0.7 0.7) (thickness 0.15)) (justify left bottom mirror))
    )
    (fp_rect (start -0.94 0.47) (end 0.94 -0.47) (layer "B.CrtYd") (width 0.05) (fill none))
    (fp_rect (start -0.499 0.249) (end 0.499 -0.249) (layer "B.Fab") (width 0.15) (fill none))
    (pad "1" smd roundrect (at -0.484 0 180) (size 0.59 0.64) (layers "B.Cu" "B.Paste" "B.Mask") (roundrect_rratio 0.25)
      (net 188 "/HDMI converter/LT9611_VDD12") (pintype "passive"))
    (pad "2" smd roundrect (at 0.484 0 180) (size 0.59 0.64) (layers "B.Cu" "B.Paste" "B.Mask") (roundrect_rratio 0.25)
      (net 1 "GND") (pintype "passive"))
  )
)
